# T6G (Grand Teton) — schematic netlist excerpt (pin names and nets, part order shuffled) for the footprints in the layout excerpt that follows; sources: Cadence DE-HDL packaged netlist, KiCad conversion of 04192023_DAF0TMB3IC0_F0TG_MB_C_brd_V02_OCP.brd

R3431  Q_RES  100K 1% EMPTY  pkg 0402LF  page 126 : A = GPU_HMC_PRSNT_N ; B = GND
PC115_4  Q_CAP  0.1UF 25V 10% X7R  pkg 0402  page 202 : A = SW_P12V_AUX_PVDDCR_CPU1_P0_FLT ; B = GND

(kicad_pcb
	(version 20260206)
	(generator "pcbnew")
	(generator_version "10.0")
	(general
		(thickness 1.6)
		(legacy_teardrops no)
	)
	(paper "A4")
	(title_block
		(title "04192023_DAF0TMB3IC0_F0TG_MB_C_brd_V02_OCP.brd")
		(comment 1 "Grand Teton / footprints 719-720 of 8354")
	)
	(layers
		(0 "F.Cu" signal "TOP")
		(4 "In1.Cu" signal "GND")
		(6 "In2.Cu" signal "IN1")
		(8 "In3.Cu" signal "GND1")
		(10 "In4.Cu" signal "IN2")
		(12 "In5.Cu" signal "GND2")
		(14 "In6.Cu" signal "IN3")
		(16 "In7.Cu" signal "GND3")
		(18 "In8.Cu" signal "VCC")
		(20 "In9.Cu" signal "VCC1")
		(22 "In10.Cu" signal "GND4")
		(24 "In11.Cu" signal "IN4")
		(26 "In12.Cu" signal "GND5")
		(28 "In13.Cu" signal "IN5")
		(30 "In14.Cu" signal "GND6")
		(32 "In15.Cu" signal "IN6")
		(34 "In16.Cu" signal "GND7")
		(2 "B.Cu" signal "BOTTOM")
		(9 "F.Adhes" user "F.Adhesive")
		(11 "B.Adhes" user "B.Adhesive")
		(13 "F.Paste" user "Package Geometry/Pastemask Top")
		(15 "B.Paste" user "Package Geometry/Pastemask Bottom")
		(5 "F.SilkS" user "Ref Des/Silkscreen Top")
		(7 "B.SilkS" user "Ref Des/Silkscreen Bottom")
		(1 "F.Mask" user "Board Geometry/Soldermask Top")
		(3 "B.Mask" user "Board Geometry/Soldermask Bottom")
		(17 "Dwgs.User" user "User.Drawings")
		(19 "Cmts.User" user "User.Comments")
		(21 "Eco1.User" user "User.Eco1")
		(23 "Eco2.User" user "User.Eco2")
		(25 "Edge.Cuts" user "Board Geometry/Outline")
		(27 "Margin" user)
		(31 "F.CrtYd" user "Package Geometry/Place Bound Top")
		(29 "B.CrtYd" user "Package Geometry/Place Bound Bottom")
		(35 "F.Fab" user "Ref Des/Assembly Top")
		(33 "B.Fab" user "Ref Des/Assembly Bottom")
	)
	(footprint ""
		(layer "F.Cu")
		(at 120.396 -420.497)
		(property "Reference" "R3431"
			(at 0 0 0)
			(layer "F.SilkS")
			(hide yes)
			(effects
				(font
					(size 1.27 1.27)
				)
			)
		)
		(property "Value" ""
			(at 0 0 0)
			(layer "F.Fab")
			(effects
				(font
					(size 1.27 1.27)
				)
			)
		)
		(duplicate_pad_numbers_are_jumpers no)
		(fp_line
			(start -0.7874 -0.4064)
			(end 0.7874 -0.4064)
			(stroke
				(width 0.1524)
				(type default)
			)
			(layer "F.SilkS")
		)
		(fp_line
			(start -0.7874 0.4064)
			(end -0.7874 -0.4064)
			(stroke
				(width 0.1524)
				(type default)
			)
			(layer "F.SilkS")
		)
		(fp_line
			(start 0.7874 -0.4064)
			(end 0.7874 0.4064)
			(stroke
				(width 0.1524)
				(type default)
			)
			(layer "F.SilkS")
		)
		(fp_line
			(start 0.7874 0.4064)
			(end -0.7874 0.4064)
			(stroke
				(width 0.1524)
				(type default)
			)
			(layer "F.SilkS")
		)
		(fp_line
			(start -0.67945 -0.305054)
			(end -0.12065 -0.305054)
			(stroke
				(width 0.1)
				(type default)
			)
			(layer "F.Fab")
		)
		(fp_line
			(start -0.67945 0.3048)
			(end -0.67945 -0.305054)
			(stroke
				(width 0.1)
				(type default)
			)
			(layer "F.Fab")
		)
		(fp_line
			(start -0.12065 -0.305054)
			(end -0.12065 -0.2794)
			(stroke
				(width 0.1)
				(type default)
			)
			(layer "F.Fab")
		)
		(fp_line
			(start -0.12065 -0.2794)
			(end 0.12065 -0.2794)
			(stroke
				(width 0.1)
				(type default)
			)
			(layer "F.Fab")
		)
		(fp_line
			(start -0.12065 0.2794)
			(end -0.12065 0.3048)
			(stroke
				(width 0.1)
				(type default)
			)
			(layer "F.Fab")
		)
		(fp_line
			(start -0.12065 0.3048)
			(end -0.67945 0.3048)
			(stroke
				(width 0.1)
				(type default)
			)
			(layer "F.Fab")
		)
		(fp_line
			(start 0.120396 0.2794)
			(end -0.12065 0.2794)
			(stroke
				(width 0.1)
				(type default)
			)
			(layer "F.Fab")
		)
		(fp_line
			(start 0.120396 0.3048)
			(end 0.120396 0.2794)
			(stroke
				(width 0.1)
				(type default)
			)
			(layer "F.Fab")
		)
		(fp_line
			(start 0.12065 -0.3048)
			(end 0.67945 -0.3048)
			(stroke
				(width 0.1)
				(type default)
			)
			(layer "F.Fab")
		)
		(fp_line
			(start 0.12065 -0.2794)
			(end 0.12065 -0.3048)
			(stroke
				(width 0.1)
				(type default)
			)
			(layer "F.Fab")
		)
		(fp_line
			(start 0.67945 -0.3048)
			(end 0.67945 0.3048)
			(stroke
				(width 0.1)
				(type default)
			)
			(layer "F.Fab")
		)
		(fp_line
			(start 0.67945 0.3048)
			(end 0.120396 0.3048)
			(stroke
				(width 0.1)
				(type default)
			)
			(layer "F.Fab")
		)
		(pad "1" smd circle
			(at -0.40005 0)
			(size 0 0)
			(layers "F.Cu" "F.Mask" "F.Paste")
			(net "GPU_HMC_PRSNT_N")
		)
		(pad "2" smd circle
			(at 0.40005 0)
			(size 0 0)
			(layers "F.Cu" "F.Mask" "F.Paste")
			(net "GND")
		)
	)
	(footprint ""
		(layer "F.Cu")
		(at 313.313064 -346.863924 -90)
		(property "Reference" "PC115_4"
			(at 0 0 270)
			(layer "F.SilkS")
			(hide yes)
			(effects
				(font
					(size 1.27 1.27)
				)
			)
		)
		(property "Value" ""
			(at 0 0 270)
			(layer "F.Fab")
			(effects
				(font
					(size 1.27 1.27)
				)
			)
		)
		(duplicate_pad_numbers_are_jumpers no)
		(fp_line
			(start -0.7874 0.4064)
			(end -0.7874 -0.4064)
			(stroke
				(width 0.1524)
				(type default)
			)
			(layer "F.SilkS")
		)
		(fp_line
			(start 0.7874 0.4064)
			(end -0.7874 0.4064)
			(stroke
				(width 0.1524)
				(type default)
			)
			(layer "F.SilkS")
		)
		(fp_line
			(start -0.7874 -0.4064)
			(end 0.7874 -0.4064)
			(stroke
				(width 0.1524)
				(type default)
			)
			(layer "F.SilkS")
		)
		(fp_line
			(start 0.7874 -0.4064)
			(end 0.7874 0.4064)
			(stroke
				(width 0.1524)
				(type default)
			)
			(layer "F.SilkS")
		)
		(fp_line
			(start -0.67945 0.3048)
			(end -0.67945 -0.305054)
			(stroke
				(width 0.1)
				(type default)
			)
			(layer "F.Fab")
		)
		(fp_line
			(start -0.12065 0.3048)
			(end -0.67945 0.3048)
			(stroke
				(width 0.1)
				(type default)
			)
			(layer "F.Fab")
		)
		(fp_line
			(start 0.120396 0.3048)
			(end 0.120396 0.2794)
			(stroke
				(width 0.1)
				(type default)
			)
			(layer "F.Fab")
		)
		(fp_line
			(start 0.67945 0.3048)
			(end 0.120396 0.3048)
			(stroke
				(width 0.1)
				(type default)
			)
			(layer "F.Fab")
		)
		(fp_line
			(start -0.12065 0.2794)
			(end -0.12065 0.3048)
			(stroke
				(width 0.1)
				(type default)
			)
			(layer "F.Fab")
		)
		(fp_line
			(start 0.120396 0.2794)
			(end -0.12065 0.2794)
			(stroke
				(width 0.1)
				(type default)
			)
			(layer "F.Fab")
		)
		(fp_line
			(start -0.12065 -0.2794)
			(end 0.12065 -0.2794)
			(stroke
				(width 0.1)
				(type default)
			)
			(layer "F.Fab")
		)
		(fp_line
			(start 0.12065 -0.2794)
			(end 0.12065 -0.3048)
			(stroke
				(width 0.1)
				(type default)
			)
			(layer "F.Fab")
		)
		(fp_line
			(start 0.12065 -0.3048)
			(end 0.67945 -0.3048)
			(stroke
				(width 0.1)
				(type default)
			)
			(layer "F.Fab")
		)
		(fp_line
			(start 0.67945 -0.3048)
			(end 0.67945 0.3048)
			(stroke
				(width 0.1)
				(type default)
			)
			(layer "F.Fab")
		)
		(fp_line
			(start -0.67945 -0.305054)
			(end -0.12065 -0.305054)
			(stroke
				(width 0.1)
				(type default)
			)
			(layer "F.Fab")
		)
		(fp_line
			(start -0.12065 -0.305054)
			(end -0.12065 -0.2794)
			(stroke
				(width 0.1)
				(type default)
			)
			(layer "F.Fab")
		)
		(pad "1" smd circle
			(at -0.40005 0 270)
			(size 0 0)
			(layers "F.Cu" "F.Mask" "F.Paste")
			(net "SW_P12V_AUX_PVDDCR_CPU1_P0_FLT")
		)
		(pad "2" smd circle
			(at 0.40005 0 270)
			(size 0 0)
			(layers "F.Cu" "F.Mask" "F.Paste")
			(net "GND")
		)
	)
)
